# TIMECARD (Time Appliance Project (Time Card)) — schematic netlist excerpt (pin names and nets, part order shuffled) for the footprints in the layout excerpt that follows; sources: Cadence DE-HDL packaged netlist, KiCad conversion of R4006-B0001-02_R01.brd

R36  RESISTOR  10KOHM 1%  pkg SMC_0402R_H016  page 28 : \1\ = XP3R3V_COMP ; \2\ = UNNAMED_517_CAPACITOR_I17_1
C248  CAPACITOR  0.1UF 25V 10%  pkg SMC_0402R_H022  page 15 : \1\ = VDD3V3_OSC_200M ; \2\ = SG

(kicad_pcb
	(version 20260206)
	(generator "pcbnew")
	(generator_version "10.0")
	(general
		(thickness 1.6)
		(legacy_teardrops no)
	)
	(paper "A4")
	(title_block
		(title "timecard-production-celestica-r4006 — R4006-B0001-02_R01.brd")
		(comment 1 "Time Appliance Project (Time Card) / footprints 843-844 of 1113")
	)
	(layers
		(0 "F.Cu" signal "TOP")
		(4 "In1.Cu" signal "L02_GND1")
		(6 "In2.Cu" signal "L03_SIG1")
		(8 "In3.Cu" signal "L04_GND2")
		(10 "In4.Cu" signal "L05_VCC1")
		(12 "In5.Cu" signal "L06_VCC2")
		(14 "In6.Cu" signal "L07_GND3")
		(16 "In7.Cu" signal "L08_SIG2")
		(18 "In8.Cu" signal "L09_GND4")
		(2 "B.Cu" signal "BOTTOM")
		(9 "F.Adhes" user "F.Adhesive")
		(11 "B.Adhes" user "B.Adhesive")
		(13 "F.Paste" user "Package Geometry/Pastemask Top")
		(15 "B.Paste" user "Package Geometry/Pastemask Bottom")
		(5 "F.SilkS" user "Ref Des/Silkscreen Top")
		(7 "B.SilkS" user "Ref Des/Silkscreen Bottom")
		(1 "F.Mask" user "Board Geometry/Soldermask Top")
		(3 "B.Mask" user "Board Geometry/Soldermask Bottom")
		(17 "Dwgs.User" user "User.Drawings")
		(19 "Cmts.User" user "User.Comments")
		(21 "Eco1.User" user "User.Eco1")
		(23 "Eco2.User" user "User.Eco2")
		(25 "Edge.Cuts" user "Board Geometry/Outline")
		(27 "Margin" user)
		(31 "F.CrtYd" user "Package Geometry/Place Bound Top")
		(29 "B.CrtYd" user "Package Geometry/Place Bound Bottom")
		(35 "F.Fab" user "Ref Des/Assembly Top")
		(33 "B.Fab" user "Ref Des/Assembly Bottom")
	)
	(footprint ""
		(layer "B.Cu")
		(at 109.728 -23.876 -90)
		(property "Reference" "C248"
			(at -0.127 2.96037 270)
			(unlocked yes)
			(layer "B.SilkS")
			(effects
				(font
					(size 0.7874 0.5842)
					(thickness 0.1524)
				)
				(justify mirror)
			)
		)
		(property "Value" "VAL*"
			(at -0.0762 2.067306 270)
			(unlocked yes)
			(layer "B.Fab")
			(hide yes)
			(effects
				(font
					(size 0.7874 0.5842)
					(thickness 0.1524)
				)
				(justify mirror)
			)
		)
		(property "Device Type" "CAPACITOR-G105-0B104-EK,0.1UF,A"
			(at -0.0508 1.127506 270)
			(unlocked yes)
			(layer "B.Fab")
			(hide yes)
			(effects
				(font
					(size 0.7874 0.5842)
					(thickness 0.1524)
				)
				(justify mirror)
			)
		)
		(property "User Part Number" "PARTNUM*"
			(at -0.1016 4.023106 270)
			(unlocked yes)
			(layer "Cmts.User")
			(hide yes)
			(effects
				(font
					(size 0.7874 0.5842)
					(thickness 0.1524)
				)
				(justify mirror)
			)
		)
		(property "Tolerance" "TOL*"
			(at -0.0762 3.032506 270)
			(unlocked yes)
			(layer "Cmts.User")
			(hide yes)
			(effects
				(font
					(size 0.7874 0.5842)
					(thickness 0.1524)
				)
				(justify mirror)
			)
		)
		(duplicate_pad_numbers_are_jumpers no)
		(fp_line
			(start -1.143 0.5588)
			(end -1.143 -0.5588)
			(stroke
				(width 0.1)
				(type default)
			)
			(layer "B.SilkS")
		)
		(fp_line
			(start 1.143 0.5588)
			(end -1.143 0.5588)
			(stroke
				(width 0.1)
				(type default)
			)
			(layer "B.SilkS")
		)
		(fp_line
			(start -1.143 -0.5588)
			(end 1.143 -0.5588)
			(stroke
				(width 0.1)
				(type default)
			)
			(layer "B.SilkS")
		)
		(fp_line
			(start 1.143 -0.5588)
			(end 1.143 0.5588)
			(stroke
				(width 0.1)
				(type default)
			)
			(layer "B.SilkS")
		)
		(fp_rect
			(start 1.143 -0.5588)
			(end -1.143 0.5588)
			(stroke
				(width 0)
				(type default)
			)
			(fill no)
			(layer "B.CrtYd")
		)
		(fp_line
			(start -0.508 0.3048)
			(end -0.508 -0.3048)
			(stroke
				(width 0.1)
				(type default)
			)
			(layer "B.Fab")
		)
		(fp_line
			(start 0.508 0.3048)
			(end -0.508 0.3048)
			(stroke
				(width 0.1)
				(type default)
			)
			(layer "B.Fab")
		)
		(fp_line
			(start -0.508 -0.3048)
			(end 0.508 -0.3048)
			(stroke
				(width 0.1)
				(type default)
			)
			(layer "B.Fab")
		)
		(fp_line
			(start 0.508 -0.3048)
			(end 0.508 0.3048)
			(stroke
				(width 0.1)
				(type default)
			)
			(layer "B.Fab")
		)
		(pad "1" smd rect
			(at 0.5334 0 90)
			(size 0.7112 0.6096)
			(layers "B.Cu" "B.Mask" "B.Paste")
			(net "VDD3V3_OSC_200M")
		)
		(pad "2" smd rect
			(at -0.5334 0 90)
			(size 0.7112 0.6096)
			(layers "B.Cu" "B.Mask" "B.Paste")
			(net "SG")
		)
		(zone
			(layer "B.Cu")
			(hatch none 0.5)
			(connect_pads
				(clearance 0)
			)
			(min_thickness 0.25)
			(keepout
				(tracks allowed)
				(vias not_allowed)
				(pads allowed)
				(copperpour not_allowed)
				(footprints allowed)
			)
			(placement
				(enabled no)
				(sheetname "")
			)
			(fill
				(thermal_gap 0.5)
				(thermal_bridge_width 0.5)
				(island_removal_mode 0)
			)
			(polygon
				(pts
					(xy 110.0328 -23.7998) (xy 110.0328 -23.9522) (xy 109.4232 -23.9522) (xy 109.4232 -23.7998)
				)
			)
		)
	)
	(footprint ""
		(layer "B.Cu")
		(at 89.9922 -101.2698 180)
		(property "Reference" "R36"
			(at -3.683 -0.03937 0)
			(unlocked yes)
			(layer "B.SilkS")
			(effects
				(font
					(size 0.7874 0.5842)
					(thickness 0.1524)
				)
				(justify mirror)
			)
		)
		(property "Value" "VAL*"
			(at -0.02032 2.13233 180)
			(unlocked yes)
			(layer "B.Fab")
			(hide yes)
			(effects
				(font
					(size 0.7874 0.5842)
					(thickness 0.1524)
				)
				(justify mirror)
			)
		)
		(property "Tolerance" "TOL*"
			(at -0.044704 3.05435 180)
			(unlocked yes)
			(layer "Cmts.User")
			(hide yes)
			(effects
				(font
					(size 0.7874 0.5842)
					(thickness 0.1524)
				)
				(justify mirror)
			)
		)
		(property "User Part Number" "PARTNUM*"
			(at -0.02032 4.024884 180)
			(unlocked yes)
			(layer "Cmts.User")
			(hide yes)
			(effects
				(font
					(size 0.7874 0.5842)
					(thickness 0.1524)
				)
				(justify mirror)
			)
		)
		(property "Device Type" "RESISTOR-G155-11002-01,10KOHM,A"
			(at -0.008382 1.210564 180)
			(unlocked yes)
			(layer "B.Fab")
			(hide yes)
			(effects
				(font
					(size 0.7874 0.5842)
					(thickness 0.1524)
				)
				(justify mirror)
			)
		)
		(duplicate_pad_numbers_are_jumpers no)
		(fp_line
			(start 1.143 0.5588)
			(end -1.143 0.5588)
			(stroke
				(width 0.1)
				(type default)
			)
			(layer "B.SilkS")
		)
		(fp_line
			(start 1.143 -0.5588)
			(end 1.143 0.5588)
			(stroke
				(width 0.1)
				(type default)
			)
			(layer "B.SilkS")
		)
		(fp_line
			(start -1.143 0.5588)
			(end -1.143 -0.5588)
			(stroke
				(width 0.1)
				(type default)
			)
			(layer "B.SilkS")
		)
		(fp_line
			(start -1.143 -0.5588)
			(end 1.143 -0.5588)
			(stroke
				(width 0.1)
				(type default)
			)
			(layer "B.SilkS")
		)
		(fp_rect
			(start 1.143 -0.5588)
			(end -1.143 0.5588)
			(stroke
				(width 0)
				(type default)
			)
			(fill no)
			(layer "B.CrtYd")
		)
		(fp_line
			(start 0.508 0.3048)
			(end -0.508 0.3048)
			(stroke
				(width 0.1)
				(type default)
			)
			(layer "B.Fab")
		)
		(fp_line
			(start 0.508 -0.3048)
			(end 0.508 0.3048)
			(stroke
				(width 0.1)
				(type default)
			)
			(layer "B.Fab")
		)
		(fp_line
			(start -0.508 0.3048)
			(end -0.508 -0.3048)
			(stroke
				(width 0.1)
				(type default)
			)
			(layer "B.Fab")
		)
		(fp_line
			(start -0.508 -0.3048)
			(end 0.508 -0.3048)
			(stroke
				(width 0.1)
				(type default)
			)
			(layer "B.Fab")
		)
		(pad "1" smd rect
			(at 0.5334 0)
			(size 0.7112 0.6096)
			(layers "B.Cu" "B.Mask" "B.Paste")
			(net "XP3R3V_COMP")
		)
		(pad "2" smd rect
			(at -0.5334 0)
			(size 0.7112 0.6096)
			(layers "B.Cu" "B.Mask" "B.Paste")
			(net "UNNAMED_517_CAPACITOR_I17_1")
		)
		(zone
			(layer "B.Cu")
			(hatch none 0.5)
			(connect_pads
				(clearance 0)
			)
			(min_thickness 0.25)
			(keepout
				(tracks allowed)
				(vias not_allowed)
				(pads allowed)
				(copperpour not_allowed)
				(footprints allowed)
			)
			(placement
				(enabled no)
				(sheetname "")
			)
			(fill
				(thermal_gap 0.5)
				(thermal_bridge_width 0.5)
				(island_removal_mode 0)
			)
			(polygon
				(pts
					(xy 89.916 -100.965) (xy 90.0684 -100.965) (xy 90.0684 -101.5746) (xy 89.916 -101.5746)
				)
			)
		)
	)
)
